FILE_TYPE = CONNECTIVITY;
{Allegro Design Entry HDL 16.6-p007 (v16-6-112F) 10/10/2012}
"PAGE_NUMBER" = 32;
0"NC";
1"P3E_CPU0_PE3_OCP_TXN<15:0>";
2"P3E_CPU0_PE3_OCP_TXP<15:0>";
3"P3E_CPU0_PE3_OCP_RXN<15:0>";
4"P3E_CPU0_PE3_OCP_RXP<15:0>";
5"P3E_CPU0_PE3_OCP_RXN<3>";
6"P3E_CPU0_PE3_OCP_RXP<0>";
7"P3E_CPU0_PE3_OCP_RXP<1>";
8"P3E_CPU0_PE3_OCP_RXP<2>";
9"P3E_CPU0_PE3_OCP_RXP<3>";
10"P3E_CPU0_PE3_OCP_RXN<0>";
11"P3E_CPU0_PE3_OCP_RXN<1>";
12"P3E_CPU0_PE3_OCP_RXN<2>";
13"P3E_CPU0_PE3_OCP_RXP<4>";
14"P3E_CPU0_PE3_OCP_RXP<5>";
15"P3E_CPU0_PE3_OCP_RXP<6>";
16"P3E_CPU0_PE3_OCP_RXP<7>";
17"P3E_CPU0_PE3_OCP_RXP<8>";
18"P3E_CPU0_PE3_OCP_RXP<9>";
19"P3E_CPU0_PE3_OCP_RXP<10>";
20"P3E_CPU0_PE3_OCP_RXP<11>";
21"P3E_CPU0_PE3_OCP_RXP<12>";
22"P3E_CPU0_PE3_OCP_RXP<13>";
23"P3E_CPU0_PE3_OCP_RXP<14>";
24"P3E_CPU0_PE3_OCP_RXP<15>";
25"P3E_CPU0_PE3_OCP_RXN<4>";
26"P3E_CPU0_PE3_OCP_RXN<5>";
27"P3E_CPU0_PE3_OCP_RXN<6>";
28"P3E_CPU0_PE3_OCP_RXN<7>";
29"P3E_CPU0_PE3_OCP_RXN<8>";
30"P3E_CPU0_PE3_OCP_RXN<9>";
31"P3E_CPU0_PE3_OCP_RXN<10>";
32"P3E_CPU0_PE3_OCP_RXN<11>";
33"P3E_CPU0_PE3_OCP_RXN<12>";
34"P3E_CPU0_PE3_OCP_RXN<13>";
35"P3E_CPU0_PE3_OCP_RXN<14>";
36"P3E_CPU0_PE3_OCP_RXN<15>";
37"P3E_CPU0_PE3_OCP_TXP<0>";
38"P3E_CPU0_PE3_OCP_TXP<1>";
39"P3E_CPU0_PE3_OCP_TXP<2>";
40"P3E_CPU0_PE3_OCP_TXP<3>";
41"P3E_CPU0_PE3_OCP_TXN<0>";
42"P3E_CPU0_PE3_OCP_TXN<1>";
43"P3E_CPU0_PE3_OCP_TXN<2>";
44"P3E_CPU0_PE3_OCP_TXN<3>";
45"P3E_CPU0_PE3_OCP_TXP<4>";
46"P3E_CPU0_PE3_OCP_TXP<5>";
47"P3E_CPU0_PE3_OCP_TXP<6>";
48"P3E_CPU0_PE3_OCP_TXP<7>";
49"P3E_CPU0_PE3_OCP_TXP<8>";
50"P3E_CPU0_PE3_OCP_TXP<9>";
51"P3E_CPU0_PE3_OCP_TXP<10>";
52"P3E_CPU0_PE3_OCP_TXP<11>";
53"P3E_CPU0_PE3_OCP_TXP<12>";
54"P3E_CPU0_PE3_OCP_TXP<13>";
55"P3E_CPU0_PE3_OCP_TXP<14>";
56"P3E_CPU0_PE3_OCP_TXP<15>";
57"P3E_CPU0_PE3_OCP_TXN<4>";
58"P3E_CPU0_PE3_OCP_TXN<5>";
59"P3E_CPU0_PE3_OCP_TXN<6>";
60"P3E_CPU0_PE3_OCP_TXN<7>";
61"P3E_CPU0_PE3_OCP_TXN<8>";
62"P3E_CPU0_PE3_OCP_TXN<9>";
63"P3E_CPU0_PE3_OCP_TXN<10>";
64"P3E_CPU0_PE3_OCP_TXN<11>";
65"P3E_CPU0_PE3_OCP_TXN<12>";
66"P3E_CPU0_PE3_OCP_TXN<13>";
67"P3E_CPU0_PE3_OCP_TXN<14>";
68"P3E_CPU0_PE3_OCP_TXN<15>";
%"TAP"
"1","(-5875,2025)","2","mstr_standard","I15";
;
HDL_TAP"TRUE"
BODY_TYPE"PLUMBING"
CDS_LIB"mstr_standard";
"B \NAC \NWC"4;
"S \NAC"
BN"3"9;
%"TAP"
"1","(-6025,2625)","2","mstr_standard","I20";
;
HDL_TAP"TRUE"
BODY_TYPE"PLUMBING"
CDS_LIB"mstr_standard";
"B \NAC \NWC"3;
"S \NAC"
BN"8"29;
%"TAP"
"1","(-6025,2675)","2","mstr_standard","I21";
;
HDL_TAP"TRUE"
BODY_TYPE"PLUMBING"
CDS_LIB"mstr_standard";
"B \NAC \NWC"3;
"S \NAC"
BN"9"30;
%"TAP"
"1","(-6025,2725)","2","mstr_standard","I22";
;
HDL_TAP"TRUE"
BODY_TYPE"PLUMBING"
CDS_LIB"mstr_standard";
"B \NAC \NWC"3;
"S \NAC"
BN"10"31;
%"TAP"
"1","(-6025,2775)","2","mstr_standard","I23";
;
HDL_TAP"TRUE"
BODY_TYPE"PLUMBING"
CDS_LIB"mstr_standard";
"B \NAC \NWC"3;
"S \NAC"
BN"11"32;
%"TAP"
"1","(-5875,2875)","2","mstr_standard","I24";
;
HDL_TAP"TRUE"
BODY_TYPE"PLUMBING"
CDS_LIB"mstr_standard";
"B \NAC \NWC"4;
"S \NAC"
BN"8"17;
%"TAP"
"1","(-5875,2975)","2","mstr_standard","I25";
;
HDL_TAP"TRUE"
BODY_TYPE"PLUMBING"
CDS_LIB"mstr_standard";
"B \NAC \NWC"4;
"S \NAC"
BN"10"19;
%"TAP"
"1","(-5875,2925)","2","mstr_standard","I26";
;
HDL_TAP"TRUE"
BODY_TYPE"PLUMBING"
CDS_LIB"mstr_standard";
"B \NAC \NWC"4;
"S \NAC"
BN"9"18;
%"TAP"
"1","(-5875,3025)","2","mstr_standard","I27";
;
HDL_TAP"TRUE"
BODY_TYPE"PLUMBING"
CDS_LIB"mstr_standard";
"B \NAC \NWC"4;
"S \NAC"
BN"11"20;
%"TAP"
"1","(-6025,3125)","2","mstr_standard","I28";
;
HDL_TAP"TRUE"
BODY_TYPE"PLUMBING"
CDS_LIB"mstr_standard";
"B \NAC \NWC"3;
"S \NAC"
BN"12"33;
%"TAP"
"1","(-6025,3175)","2","mstr_standard","I29";
;
HDL_TAP"TRUE"
BODY_TYPE"PLUMBING"
CDS_LIB"mstr_standard";
"B \NAC \NWC"3;
"S \NAC"
BN"13"34;
%"TAP"
"1","(-6025,1625)","2","mstr_standard","I3";
;
HDL_TAP"TRUE"
BODY_TYPE"PLUMBING"
CDS_LIB"mstr_standard";
"B \NAC \NWC"3;
"S \NAC"
BN"0"10;
%"TAP"
"1","(-6025,3275)","2","mstr_standard","I30";
;
HDL_TAP"TRUE"
BODY_TYPE"PLUMBING"
CDS_LIB"mstr_standard";
"B \NAC \NWC"3;
"S \NAC"
BN"15"36;
%"TAP"
"1","(-6025,3225)","2","mstr_standard","I31";
;
HDL_TAP"TRUE"
BODY_TYPE"PLUMBING"
CDS_LIB"mstr_standard";
"B \NAC \NWC"3;
"S \NAC"
BN"14"35;
%"TAP"
"1","(-5875,3375)","2","mstr_standard","I32";
;
HDL_TAP"TRUE"
BODY_TYPE"PLUMBING"
CDS_LIB"mstr_standard";
"B \NAC \NWC"4;
"S \NAC"
BN"12"21;
%"TAP"
"1","(-5875,3425)","2","mstr_standard","I33";
;
HDL_TAP"TRUE"
BODY_TYPE"PLUMBING"
CDS_LIB"mstr_standard";
"B \NAC \NWC"4;
"S \NAC"
BN"13"22;
%"TAP"
"1","(-5875,3475)","2","mstr_standard","I34";
;
HDL_TAP"TRUE"
BODY_TYPE"PLUMBING"
CDS_LIB"mstr_standard";
"B \NAC \NWC"4;
"S \NAC"
BN"14"23;
%"TAP"
"1","(-5875,3525)","2","mstr_standard","I35";
;
HDL_TAP"TRUE"
BODY_TYPE"PLUMBING"
CDS_LIB"mstr_standard";
"B \NAC \NWC"4;
"S \NAC"
BN"15"24;
%"TAP"
"1","(-3000,1875)","0","mstr_standard","I36";
;
HDL_TAP"TRUE"
BODY_TYPE"PLUMBING"
CDS_LIB"mstr_standard";
"B \NAC \NWC"2;
"S \NAC"
BN"0"37;
%"TAP"
"1","(-3000,1975)","0","mstr_standard","I37";
;
HDL_TAP"TRUE"
BODY_TYPE"PLUMBING"
CDS_LIB"mstr_standard";
"B \NAC \NWC"2;
"S \NAC"
BN"2"39;
%"TAP"
"1","(-3000,1925)","0","mstr_standard","I38";
;
HDL_TAP"TRUE"
BODY_TYPE"PLUMBING"
CDS_LIB"mstr_standard";
"B \NAC \NWC"2;
"S \NAC"
BN"1"38;
%"TAP"
"1","(-2850,1625)","0","mstr_standard","I39";
;
HDL_TAP"TRUE"
BODY_TYPE"PLUMBING"
CDS_LIB"mstr_standard";
"B \NAC \NWC"1;
"S \NAC"
BN"0"41;
%"TAP"
"1","(-6025,1675)","2","mstr_standard","I4";
;
HDL_TAP"TRUE"
BODY_TYPE"PLUMBING"
CDS_LIB"mstr_standard";
"B \NAC \NWC"3;
"S \NAC"
BN"1"11;
%"TAP"
"1","(-2850,1675)","0","mstr_standard","I40";
;
HDL_TAP"TRUE"
BODY_TYPE"PLUMBING"
CDS_LIB"mstr_standard";
"B \NAC \NWC"1;
"S \NAC"
BN"1"42;
%"TAP"
"1","(-2850,1725)","0","mstr_standard","I41";
;
HDL_TAP"TRUE"
BODY_TYPE"PLUMBING"
CDS_LIB"mstr_standard";
"B \NAC \NWC"1;
"S \NAC"
BN"2"43;
%"TAP"
"1","(-2850,1775)","0","mstr_standard","I42";
;
HDL_TAP"TRUE"
BODY_TYPE"PLUMBING"
CDS_LIB"mstr_standard";
"B \NAC \NWC"1;
"S \NAC"
BN"3"44;
%"TAP"
"1","(-3000,2475)","0","mstr_standard","I43";
;
HDL_TAP"TRUE"
BODY_TYPE"PLUMBING"
CDS_LIB"mstr_standard";
"B \NAC \NWC"2;
"S \NAC"
BN"6"47;
%"TAP"
"1","(-3000,2525)","0","mstr_standard","I44";
;
HDL_TAP"TRUE"
BODY_TYPE"PLUMBING"
CDS_LIB"mstr_standard";
"B \NAC \NWC"2;
"S \NAC"
BN"7"48;
%"TAP"
"1","(-3000,2425)","0","mstr_standard","I45";
;
HDL_TAP"TRUE"
BODY_TYPE"PLUMBING"
CDS_LIB"mstr_standard";
"B \NAC \NWC"2;
"S \NAC"
BN"5"46;
%"TAP"
"1","(-3000,2375)","0","mstr_standard","I46";
;
HDL_TAP"TRUE"
BODY_TYPE"PLUMBING"
CDS_LIB"mstr_standard";
"B \NAC \NWC"2;
"S \NAC"
BN"4"45;
%"TAP"
"1","(-3000,2025)","0","mstr_standard","I47";
;
HDL_TAP"TRUE"
BODY_TYPE"PLUMBING"
CDS_LIB"mstr_standard";
"B \NAC \NWC"2;
"S \NAC"
BN"3"40;
%"TAP"
"1","(-2850,2125)","0","mstr_standard","I48";
;
HDL_TAP"TRUE"
BODY_TYPE"PLUMBING"
CDS_LIB"mstr_standard";
"B \NAC \NWC"1;
"S \NAC"
BN"4"57;
%"TAP"
"1","(-2850,2175)","0","mstr_standard","I49";
;
HDL_TAP"TRUE"
BODY_TYPE"PLUMBING"
CDS_LIB"mstr_standard";
"B \NAC \NWC"1;
"S \NAC"
BN"5"58;
%"TAP"
"1","(-6025,1725)","2","mstr_standard","I5";
;
HDL_TAP"TRUE"
BODY_TYPE"PLUMBING"
CDS_LIB"mstr_standard";
"B \NAC \NWC"3;
"S \NAC"
BN"2"12;
%"TAP"
"1","(-2850,2225)","0","mstr_standard","I50";
;
HDL_TAP"TRUE"
BODY_TYPE"PLUMBING"
CDS_LIB"mstr_standard";
"B \NAC \NWC"1;
"S \NAC"
BN"6"59;
%"TAP"
"1","(-2850,2275)","0","mstr_standard","I51";
;
HDL_TAP"TRUE"
BODY_TYPE"PLUMBING"
CDS_LIB"mstr_standard";
"B \NAC \NWC"1;
"S \NAC"
BN"7"60;
%"TAP"
"1","(-3000,2975)","0","mstr_standard","I52";
;
HDL_TAP"TRUE"
BODY_TYPE"PLUMBING"
CDS_LIB"mstr_standard";
"B \NAC \NWC"2;
"S \NAC"
BN"10"51;
%"TAP"
"1","(-3000,3025)","0","mstr_standard","I53";
;
HDL_TAP"TRUE"
BODY_TYPE"PLUMBING"
CDS_LIB"mstr_standard";
"B \NAC \NWC"2;
"S \NAC"
BN"11"52;
%"TAP"
"1","(-3000,2925)","0","mstr_standard","I54";
;
HDL_TAP"TRUE"
BODY_TYPE"PLUMBING"
CDS_LIB"mstr_standard";
"B \NAC \NWC"2;
"S \NAC"
BN"9"50;
%"TAP"
"1","(-3000,2875)","0","mstr_standard","I55";
;
HDL_TAP"TRUE"
BODY_TYPE"PLUMBING"
CDS_LIB"mstr_standard";
"B \NAC \NWC"2;
"S \NAC"
BN"8"49;
%"TAP"
"1","(-2850,2625)","0","mstr_standard","I56";
;
HDL_TAP"TRUE"
BODY_TYPE"PLUMBING"
CDS_LIB"mstr_standard";
"B \NAC \NWC"1;
"S \NAC"
BN"8"61;
%"TAP"
"1","(-2850,2725)","0","mstr_standard","I57";
;
HDL_TAP"TRUE"
BODY_TYPE"PLUMBING"
CDS_LIB"mstr_standard";
"B \NAC \NWC"1;
"S \NAC"
BN"10"63;
%"TAP"
"1","(-2850,2675)","0","mstr_standard","I58";
;
HDL_TAP"TRUE"
BODY_TYPE"PLUMBING"
CDS_LIB"mstr_standard";
"B \NAC \NWC"1;
"S \NAC"
BN"9"62;
%"TAP"
"1","(-2850,2775)","0","mstr_standard","I59";
;
HDL_TAP"TRUE"
BODY_TYPE"PLUMBING"
CDS_LIB"mstr_standard";
"B \NAC \NWC"1;
"S \NAC"
BN"11"64;
%"TAP"
"1","(-6025,1775)","2","mstr_standard","I6";
;
HDL_TAP"TRUE"
BODY_TYPE"PLUMBING"
CDS_LIB"mstr_standard";
"B \NAC \NWC"3;
"S \NAC"
BN"3"5;
%"TAP"
"1","(-3000,3425)","0","mstr_standard","I60";
;
HDL_TAP"TRUE"
BODY_TYPE"PLUMBING"
CDS_LIB"mstr_standard";
"B \NAC \NWC"2;
"S \NAC"
BN"13"54;
%"TAP"
"1","(-3000,3525)","0","mstr_standard","I61";
;
HDL_TAP"TRUE"
BODY_TYPE"PLUMBING"
CDS_LIB"mstr_standard";
"B \NAC \NWC"2;
"S \NAC"
BN"15"56;
%"TAP"
"1","(-3000,3375)","0","mstr_standard","I62";
;
HDL_TAP"TRUE"
BODY_TYPE"PLUMBING"
CDS_LIB"mstr_standard";
"B \NAC \NWC"2;
"S \NAC"
BN"12"53;
%"TAP"
"1","(-3000,3475)","0","mstr_standard","I63";
;
HDL_TAP"TRUE"
BODY_TYPE"PLUMBING"
CDS_LIB"mstr_standard";
"B \NAC \NWC"2;
"S \NAC"
BN"14"55;
%"TAP"
"1","(-2850,3125)","0","mstr_standard","I64";
;
HDL_TAP"TRUE"
BODY_TYPE"PLUMBING"
CDS_LIB"mstr_standard";
"B \NAC \NWC"1;
"S \NAC"
BN"12"65;
%"TAP"
"1","(-2850,3175)","0","mstr_standard","I65";
;
HDL_TAP"TRUE"
BODY_TYPE"PLUMBING"
CDS_LIB"mstr_standard";
"B \NAC \NWC"1;
"S \NAC"
BN"13"66;
%"TAP"
"1","(-2850,3275)","0","mstr_standard","I66";
;
HDL_TAP"TRUE"
BODY_TYPE"PLUMBING"
CDS_LIB"mstr_standard";
"B \NAC \NWC"1;
"S \NAC"
BN"15"68;
%"TAP"
"1","(-2850,3225)","0","mstr_standard","I67";
;
HDL_TAP"TRUE"
BODY_TYPE"PLUMBING"
CDS_LIB"mstr_standard";
"B \NAC \NWC"1;
"S \NAC"
BN"14"67;
%"TAP"
"1","(-5875,1875)","2","mstr_standard","I7";
;
HDL_TAP"TRUE"
BODY_TYPE"PLUMBING"
CDS_LIB"mstr_standard";
"B \NAC \NWC"4;
"S \NAC"
BN"0"6;
%"TAP"
"1","(-5875,1925)","2","mstr_standard","I8";
;
HDL_TAP"TRUE"
BODY_TYPE"PLUMBING"
CDS_LIB"mstr_standard";
"B \NAC \NWC"4;
"S \NAC"
BN"1"7;
%"TAP"
"6","(-5875,2525)","0","mstr_standard","I81";
;
HDL_TAP"TRUE"
BODY_TYPE"PLUMBING"
CDS_LIB"mstr_standard";
"B \NAC \NWC"4;
"S \NAC"
BN"7"16;
%"TAP"
"6","(-5875,2475)","0","mstr_standard","I82";
;
HDL_TAP"TRUE"
BODY_TYPE"PLUMBING"
CDS_LIB"mstr_standard";
"B \NAC \NWC"4;
"S \NAC"
BN"6"15;
%"TAP"
"6","(-5875,2425)","0","mstr_standard","I83";
;
HDL_TAP"TRUE"
BODY_TYPE"PLUMBING"
CDS_LIB"mstr_standard";
"B \NAC \NWC"4;
"S \NAC"
BN"5"14;
%"TAP"
"6","(-5875,2375)","0","mstr_standard","I84";
;
HDL_TAP"TRUE"
BODY_TYPE"PLUMBING"
CDS_LIB"mstr_standard";
"B \NAC \NWC"4;
"S \NAC"
BN"4"13;
%"TAP"
"6","(-6025,2275)","0","mstr_standard","I85";
;
HDL_TAP"TRUE"
BODY_TYPE"PLUMBING"
CDS_LIB"mstr_standard";
"B \NAC \NWC"3;
"S \NAC"
BN"7"28;
%"TAP"
"6","(-6025,2225)","0","mstr_standard","I86";
;
HDL_TAP"TRUE"
BODY_TYPE"PLUMBING"
CDS_LIB"mstr_standard";
"B \NAC \NWC"3;
"S \NAC"
BN"6"27;
%"TAP"
"6","(-6025,2175)","0","mstr_standard","I87";
;
HDL_TAP"TRUE"
BODY_TYPE"PLUMBING"
CDS_LIB"mstr_standard";
"B \NAC \NWC"3;
"S \NAC"
BN"5"26;
%"TAP"
"6","(-6025,2125)","0","mstr_standard","I88";
;
HDL_TAP"TRUE"
BODY_TYPE"PLUMBING"
CDS_LIB"mstr_standard";
"B \NAC \NWC"3;
"S \NAC"
BN"4"25;
%"SKX_EXT_B"
"12","(-4200,2575)","0","chpset_lib","I89";
;
CDS_SEC"12"
CDS_LOCATION"U5D1"
SEC"12"
SEC_TYPE"BGA1"
CDS_LIB"chpset_lib"
PACK_TYPE"BGA1"
MATERIAL"IC"
PART_NUMBER"TBD"
LOCATION"U5D1";
"PE3_TX_DP<0>"
$PN"EC14"37;
"PE3_TX_DP<1>"
$PN"ED13"38;
"PE3_TX_DP<2>"
$PN"EB11"39;
"PE3_TX_DP<3>"
$PN"EA10"40;
"PE3_TX_DP<4>"
$PN"DY9"45;
"PE3_TX_DP<5>"
$PN"DV9"46;
"PE3_TX_DP<6>"
$PN"DT9"47;
"PE3_TX_DP<7>"
$PN"DP7"48;
"PE3_TX_DP<8>"
$PN"DN6"49;
"PE3_TX_DP<9>"
$PN"DM5"50;
"PE3_TX_DP<10>"
$PN"DK5"51;
"PE3_TX_DP<11>"
$PN"DH5"52;
"PE3_TX_DP<12>"
$PN"DG6"53;
"PE3_TX_DP<13>"
$PN"DC6"54;
"PE3_TX_DP<14>"
$PN"DA4"55;
"PE3_TX_DP<15>"
$PN"CV5"56;
"PE3_TX_DN<0>"
$PN"EE14"41;
"PE3_TX_DN<1>"
$PN"EE12"42;
"PE3_TX_DN<2>"
$PN"EC12"43;
"PE3_TX_DN<3>"
$PN"DY11"44;
"PE3_TX_DN<4>"
$PN"EB9"57;
"PE3_TX_DN<5>"
$PN"DW10"58;
"PE3_TX_DN<6>"
$PN"DU8"59;
"PE3_TX_DN<7>"
$PN"DR8"60;
"PE3_TX_DN<8>"
$PN"DM7"61;
"PE3_TX_DN<9>"
$PN"DP5"62;
"PE3_TX_DN<10>"
$PN"DL6"63;
"PE3_TX_DN<11>"
$PN"DJ4"64;
"PE3_TX_DN<12>"
$PN"DJ6"65;
"PE3_TX_DN<13>"
$PN"DD5"66;
"PE3_TX_DN<14>"
$PN"DB5"67;
"PE3_TX_DN<15>"
$PN"CY5"68;
"PE3_RX_DP<0>"
$PN"DY17"6;
"PE3_RX_DP<1>"
$PN"DU18"7;
"PE3_RX_DP<2>"
$PN"DV17"8;
"PE3_RX_DP<3>"
$PN"DR18"9;
"PE3_RX_DP<4>"
$PN"DN16"13;
"PE3_RX_DP<5>"
$PN"DP15"14;
"PE3_RX_DP<6>"
$PN"DM13"15;
"PE3_RX_DP<7>"
$PN"DJ14"16;
"PE3_RX_DP<8>"
$PN"DK13"17;
"PE3_RX_DP<9>"
$PN"DH11"18;
"PE3_RX_DP<10>"
$PN"DE12"19;
"PE3_RX_DP<11>"
$PN"DF11"20;
"PE3_RX_DP<12>"
$PN"DC12"21;
"PE3_RX_DP<13>"
$PN"DA12"22;
"PE3_RX_DP<14>"
$PN"CW10"23;
"PE3_RX_DP<15>"
$PN"CU10"24;
"PE3_RX_DN<0>"
$PN"EA18"10;
"PE3_RX_DN<1>"
$PN"DW18"11;
"PE3_RX_DN<2>"
$PN"DW16"12;
"PE3_RX_DN<3>"
$PN"DT19"5;
"PE3_RX_DN<4>"
$PN"DR16"25;
"PE3_RX_DN<5>"
$PN"DR14"26;
"PE3_RX_DN<6>"
$PN"DN14"27;
"PE3_RX_DN<7>"
$PN"DL14"28;
"PE3_RX_DN<8>"
$PN"DL12"29;
"PE3_RX_DN<9>"
$PN"DJ12"30;
"PE3_RX_DN<10>"
$PN"DG12"31;
"PE3_RX_DN<11>"
$PN"DG10"32;
"PE3_RX_DN<12>"
$PN"DD13"33;
"PE3_RX_DN<13>"
$PN"DB11"34;
"PE3_RX_DN<14>"
$PN"CY11"35;
"PE3_RX_DN<15>"
$PN"CV9"36;
%"TAP"
"1","(-5875,1975)","2","mstr_standard","I9";
;
HDL_TAP"TRUE"
BODY_TYPE"PLUMBING"
CDS_LIB"mstr_standard";
"B \NAC \NWC"4;
"S \NAC"
BN"2"8;
END.
